# SCM (Grand Teton) — schematic netlist excerpt (pin names and nets, part order shuffled) for the footprints in the layout excerpt that follows; sources: Cadence DE-HDL packaged netlist, KiCad conversion of 12092022_DA0F0TMDCD0_F0T_Management_Board_D_brd_V3_OCP.brd

R91  Q_RES  2.2K 5% CHIP  pkg 0402LF  page 23 : A = CRT_VCC5 ; B = V_BMC_LS_DDC_SDA

U50  NC7SB3157  NC7SB3157P6X IC  pkg SMLF  page 31
  B1  = UART_BIC_DBG_TX_R
  GND  = GND
  B0  = UART_6_BMC_RXD_R
  A  = UART_BIC_GF_RXD
  VCC  = P3V3_AUX
  S  = FM_BIC_DEBUG_SW_N

(kicad_pcb
	(version 20260206)
	(generator "pcbnew")
	(generator_version "10.0")
	(general
		(thickness 1.6)
		(legacy_teardrops no)
	)
	(paper "A4")
	(title_block
		(title "12092022_DA0F0TMDCD0_F0T_Management_Board_D_brd_V3_OCP.brd")
		(comment 1 "Grand Teton / footprints 491-492 of 1440")
	)
	(layers
		(0 "F.Cu" signal "TOP")
		(4 "In1.Cu" signal "GND")
		(6 "In2.Cu" signal "IN1")
		(8 "In3.Cu" signal "GND1")
		(10 "In4.Cu" signal "IN2")
		(12 "In5.Cu" signal "VCC")
		(14 "In6.Cu" signal "VCC1")
		(16 "In7.Cu" signal "IN3")
		(18 "In8.Cu" signal "GND2")
		(20 "In9.Cu" signal "IN4")
		(22 "In10.Cu" signal "GND3")
		(2 "B.Cu" signal "BOTTOM")
		(9 "F.Adhes" user "F.Adhesive")
		(11 "B.Adhes" user "B.Adhesive")
		(13 "F.Paste" user "Package Geometry/Pastemask Top")
		(15 "B.Paste" user "Package Geometry/Pastemask Bottom")
		(5 "F.SilkS" user "Ref Des/Silkscreen Top")
		(7 "B.SilkS" user "Ref Des/Silkscreen Bottom")
		(1 "F.Mask" user "Board Geometry/Soldermask Top")
		(3 "B.Mask" user "Board Geometry/Soldermask Bottom")
		(17 "Dwgs.User" user "User.Drawings")
		(19 "Cmts.User" user "User.Comments")
		(21 "Eco1.User" user "User.Eco1")
		(23 "Eco2.User" user "User.Eco2")
		(25 "Edge.Cuts" user "Board Geometry/Outline")
		(27 "Margin" user)
		(31 "F.CrtYd" user "Package Geometry/Place Bound Top")
		(29 "B.CrtYd" user "Package Geometry/Place Bound Bottom")
		(35 "F.Fab" user "Ref Des/Assembly Top")
		(33 "B.Fab" user "Ref Des/Assembly Bottom")
	)
	(footprint ""
		(layer "F.Cu")
		(at 22.225 -62.3062 90)
		(property "Reference" "U50"
			(at -3.40487 1.016 0)
			(unlocked yes)
			(layer "F.SilkS")
			(effects
				(font
					(size 0.7874 0.5842)
					(thickness 0.1524)
				)
			)
		)
		(property "Value" ""
			(at 0 0 90)
			(layer "F.Fab")
			(effects
				(font
					(size 1.27 1.27)
				)
			)
		)
		(duplicate_pad_numbers_are_jumpers no)
		(fp_line
			(start 1.7272 -1.1176)
			(end 0.254 -1.1176)
			(stroke
				(width 0.1524)
				(type default)
			)
			(layer "F.SilkS")
		)
		(fp_line
			(start 1.7272 -1.1176)
			(end 1.7272 1.1176)
			(stroke
				(width 0.1524)
				(type default)
			)
			(layer "F.SilkS")
		)
		(fp_line
			(start 0.254 -1.1176)
			(end 0 -0.7366)
			(stroke
				(width 0.1524)
				(type default)
			)
			(layer "F.SilkS")
		)
		(fp_line
			(start -0.254 -1.1176)
			(end -1.7272 -1.1176)
			(stroke
				(width 0.1524)
				(type default)
			)
			(layer "F.SilkS")
		)
		(fp_line
			(start 0 -0.7366)
			(end -0.254 -1.1176)
			(stroke
				(width 0.1524)
				(type default)
			)
			(layer "F.SilkS")
		)
		(fp_line
			(start 1.7272 1.1176)
			(end -1.7272 1.1176)
			(stroke
				(width 0.1524)
				(type default)
			)
			(layer "F.SilkS")
		)
		(fp_line
			(start -1.7272 1.1176)
			(end -1.7272 -1.1176)
			(stroke
				(width 0.1524)
				(type default)
			)
			(layer "F.SilkS")
		)
		(fp_poly
			(pts
				(xy -1.9558 -0.649986) (xy -2.7178 -0.268986) (xy -2.7178 -1.030986)
			)
			(stroke
				(width 0)
				(type default)
			)
			(fill yes)
			(layer "F.SilkS")
		)
		(fp_line
			(start 1.5748 -1.1176)
			(end -1.5748 -1.1176)
			(stroke
				(width 0.1)
				(type default)
			)
			(layer "F.Fab")
		)
		(fp_line
			(start -1.5748 -1.1176)
			(end -1.5748 1.1176)
			(stroke
				(width 0.1)
				(type default)
			)
			(layer "F.Fab")
		)
		(fp_line
			(start 1.5748 1.1176)
			(end 1.5748 -1.1176)
			(stroke
				(width 0.1)
				(type default)
			)
			(layer "F.Fab")
		)
		(fp_line
			(start -1.5748 1.1176)
			(end 1.5748 1.1176)
			(stroke
				(width 0.1)
				(type default)
			)
			(layer "F.Fab")
		)
		(fp_poly
			(pts
				(xy -1.9558 -0.649986) (xy -2.7178 -0.268986) (xy -2.7178 -1.030986)
			)
			(stroke
				(width 0)
				(type default)
			)
			(fill yes)
			(layer "F.Fab")
		)
		(pad "1" smd rect
			(at -0.999998 -0.649986)
			(size 0.3556 1.1176)
			(layers "F.Cu" "F.Mask" "F.Paste")
			(net "UART_BIC_DBG_TX_R")
		)
		(pad "2" smd rect
			(at -0.999998 0)
			(size 0.3556 1.1176)
			(layers "F.Cu" "F.Mask" "F.Paste")
			(net "GND")
		)
		(pad "3" smd rect
			(at -0.999998 0.649986)
			(size 0.3556 1.1176)
			(layers "F.Cu" "F.Mask" "F.Paste")
			(net "UART_6_BMC_RXD_R")
		)
		(pad "4" smd rect
			(at 0.999998 0.649986)
			(size 0.3556 1.1176)
			(layers "F.Cu" "F.Mask" "F.Paste")
			(net "UART_BIC_GF_RXD")
		)
		(pad "5" smd rect
			(at 0.999998 0)
			(size 0.3556 1.1176)
			(layers "F.Cu" "F.Mask" "F.Paste")
			(net "P3V3_AUX")
		)
		(pad "6" smd rect
			(at 0.999998 -0.649986)
			(size 0.3556 1.1176)
			(layers "F.Cu" "F.Mask" "F.Paste")
			(net "FM_BIC_DEBUG_SW_N")
		)
	)
	(footprint ""
		(layer "F.Cu")
		(at 27.1272 -21.971 -90)
		(property "Reference" "R91"
			(at 0 0 270)
			(layer "F.SilkS")
			(hide yes)
			(effects
				(font
					(size 1.27 1.27)
				)
			)
		)
		(property "Value" ""
			(at 0 0 270)
			(layer "F.Fab")
			(effects
				(font
					(size 1.27 1.27)
				)
			)
		)
		(duplicate_pad_numbers_are_jumpers no)
		(fp_line
			(start -0.7874 0.4064)
			(end -0.7874 -0.4064)
			(stroke
				(width 0.1524)
				(type default)
			)
			(layer "F.SilkS")
		)
		(fp_line
			(start 0.7874 0.4064)
			(end -0.7874 0.4064)
			(stroke
				(width 0.1524)
				(type default)
			)
			(layer "F.SilkS")
		)
		(fp_line
			(start -0.7874 -0.4064)
			(end 0.7874 -0.4064)
			(stroke
				(width 0.1524)
				(type default)
			)
			(layer "F.SilkS")
		)
		(fp_line
			(start 0.7874 -0.4064)
			(end 0.7874 0.4064)
			(stroke
				(width 0.1524)
				(type default)
			)
			(layer "F.SilkS")
		)
		(fp_line
			(start -0.67945 0.3048)
			(end -0.67945 -0.305054)
			(stroke
				(width 0.1)
				(type default)
			)
			(layer "F.Fab")
		)
		(fp_line
			(start -0.12065 0.3048)
			(end -0.67945 0.3048)
			(stroke
				(width 0.1)
				(type default)
			)
			(layer "F.Fab")
		)
		(fp_line
			(start 0.120396 0.3048)
			(end 0.120396 0.2794)
			(stroke
				(width 0.1)
				(type default)
			)
			(layer "F.Fab")
		)
		(fp_line
			(start 0.67945 0.3048)
			(end 0.120396 0.3048)
			(stroke
				(width 0.1)
				(type default)
			)
			(layer "F.Fab")
		)
		(fp_line
			(start -0.12065 0.2794)
			(end -0.12065 0.3048)
			(stroke
				(width 0.1)
				(type default)
			)
			(layer "F.Fab")
		)
		(fp_line
			(start 0.120396 0.2794)
			(end -0.12065 0.2794)
			(stroke
				(width 0.1)
				(type default)
			)
			(layer "F.Fab")
		)
		(fp_line
			(start -0.12065 -0.2794)
			(end 0.12065 -0.2794)
			(stroke
				(width 0.1)
				(type default)
			)
			(layer "F.Fab")
		)
		(fp_line
			(start 0.12065 -0.2794)
			(end 0.12065 -0.3048)
			(stroke
				(width 0.1)
				(type default)
			)
			(layer "F.Fab")
		)
		(fp_line
			(start 0.12065 -0.3048)
			(end 0.67945 -0.3048)
			(stroke
				(width 0.1)
				(type default)
			)
			(layer "F.Fab")
		)
		(fp_line
			(start 0.67945 -0.3048)
			(end 0.67945 0.3048)
			(stroke
				(width 0.1)
				(type default)
			)
			(layer "F.Fab")
		)
		(fp_line
			(start -0.67945 -0.305054)
			(end -0.12065 -0.305054)
			(stroke
				(width 0.1)
				(type default)
			)
			(layer "F.Fab")
		)
		(fp_line
			(start -0.12065 -0.305054)
			(end -0.12065 -0.2794)
			(stroke
				(width 0.1)
				(type default)
			)
			(layer "F.Fab")
		)
		(pad "1" smd circle
			(at -0.40005 0 270)
			(size 0 0)
			(layers "F.Cu" "F.Mask" "F.Paste")
			(net "CRT_VCC5")
		)
		(pad "2" smd circle
			(at 0.40005 0 270)
			(size 0 0)
			(layers "F.Cu" "F.Mask" "F.Paste")
			(net "V_BMC_LS_DDC_SDA")
		)
	)
)
